(kicad_pcb
	(version 20260206)
	(generator "pcbnew")
	(generator_version "10.0")
	(general
		(thickness 1.6)
		(legacy_teardrops no)
	)
	(paper "A4")
	(title_block
		(title "pdpb — Lightning_PDPB_BRD.brd")
		(comment 1 "Lightning (Wiwynn / Facebook NVMe JBOF) / footprints 1104-1109 of 1140")
	)
	(layers
		(0 "F.Cu" signal "TOP")
		(4 "In1.Cu" signal "L2GND")
		(6 "In2.Cu" signal "L3")
		(8 "In3.Cu" signal "L4VCC")
		(10 "In4.Cu" signal "L5VCC")
		(12 "In5.Cu" signal "L6")
		(14 "In6.Cu" signal "L7GND")
		(2 "B.Cu" signal "BOTTOM")
		(9 "F.Adhes" user "F.Adhesive")
		(11 "B.Adhes" user "B.Adhesive")
		(13 "F.Paste" user "Package Geometry/Pastemask Top")
		(15 "B.Paste" user "Package Geometry/Pastemask Bottom")
		(5 "F.SilkS" user "Ref Des/Silkscreen Top")
		(7 "B.SilkS" user "Ref Des/Silkscreen Bottom")
		(1 "F.Mask" user "Board Geometry/Soldermask Top")
		(3 "B.Mask" user "Board Geometry/Soldermask Bottom")
		(17 "Dwgs.User" user "User.Drawings")
		(19 "Cmts.User" user "User.Comments")
		(21 "Eco1.User" user "User.Eco1")
		(23 "Eco2.User" user "User.Eco2")
		(25 "Edge.Cuts" user "Board Geometry/Outline")
		(27 "Margin" user)
		(31 "F.CrtYd" user "Package Geometry/Place Bound Top")
		(29 "B.CrtYd" user "Package Geometry/Place Bound Bottom")
		(35 "F.Fab" user "Ref Des/Assembly Top")
		(33 "B.Fab" user "Ref Des/Assembly Bottom")
	)
	(footprint ""
		(layer "F.Cu")
		(at 30.607 -205.0034 90)
		(property "Reference" "Q86"
			(at 0 0 90)
			(layer "F.SilkS")
			(hide yes)
			(effects
				(font
					(size 1.27 1.27)
				)
			)
		)
		(property "Value" "2N7002A-7-GP"
			(at 0.127 -8.9662 90)
			(unlocked yes)
			(layer "F.Fab")
			(hide yes)
			(effects
				(font
					(size 1.016 1.016)
					(thickness 0.1524)
				)
			)
		)
		(property "Device Type" "SOT23DGS2D4H48"
			(at 0.127 -10.4902 90)
			(unlocked yes)
			(layer "F.Fab")
			(hide yes)
			(effects
				(font
					(size 1.016 1.016)
					(thickness 0.1524)
				)
			)
		)
		(duplicate_pad_numbers_are_jumpers no)
		(fp_line
			(start 1.651 -1.778)
			(end -1.651 -1.778)
			(stroke
				(width 0.1524)
				(type default)
			)
			(layer "F.SilkS")
		)
		(fp_line
			(start -1.651 -1.778)
			(end -1.651 1.778)
			(stroke
				(width 0.1524)
				(type default)
			)
			(layer "F.SilkS")
		)
		(fp_line
			(start 1.651 1.778)
			(end 1.651 -1.778)
			(stroke
				(width 0.1524)
				(type default)
			)
			(layer "F.SilkS")
		)
		(fp_line
			(start -1.651 1.778)
			(end 1.651 1.778)
			(stroke
				(width 0.1524)
				(type default)
			)
			(layer "F.SilkS")
		)
		(fp_poly
			(pts
				(xy -1.778 1.8796) (xy -1.778 -1.8796) (xy 1.778 -1.8796) (xy 1.778 1.8796)
			)
			(stroke
				(width 0)
				(type default)
			)
			(fill no)
			(layer "F.CrtYd")
		)
		(fp_poly
			(pts
				(xy -1.778 1.8796) (xy -1.778 -1.8796) (xy 1.778 -1.8796) (xy 1.778 1.8796)
			)
			(stroke
				(width 0)
				(type default)
			)
			(fill no)
			(layer "F.Fab")
		)
		(pad "D" smd custom
			(at 0 -0.9525 90)
			(size 0.1905 0.1905)
			(layers "F.Cu" "F.Mask" "F.Paste")
			(net "P12V_MOST12_GATE_D")
			(options
				(clearance outline)
				(anchor circle)
			)
			(primitives
				(gr_poly
					(pts
						(arc
							(start -0.1778 0.5715)
							(mid -0.321484 0.511984)
							(end -0.381 0.3683)
						)
						(arc
							(start -0.381 -0.3683)
							(mid -0.321484 -0.511984)
							(end -0.1778 -0.5715)
						)
						(arc
							(start 0.1778 -0.5715)
							(mid 0.321484 -0.511984)
							(end 0.381 -0.3683)
						)
						(arc
							(start 0.381 0.3683)
							(mid 0.321484 0.511984)
							(end 0.1778 0.5715)
						)
					)
					(width 0)
					(fill yes)
				)
			)
		)
		(pad "G" smd custom
			(at -0.98425 0.9525 90)
			(size 0.1905 0.1905)
			(layers "F.Cu" "F.Mask" "F.Paste")
			(net "P12V_MOST12_GATE")
			(options
				(clearance outline)
				(anchor circle)
			)
			(primitives
				(gr_poly
					(pts
						(arc
							(start -0.1778 0.5715)
							(mid -0.321484 0.511984)
							(end -0.381 0.3683)
						)
						(arc
							(start -0.381 -0.3683)
							(mid -0.321484 -0.511984)
							(end -0.1778 -0.5715)
						)
						(arc
							(start 0.1778 -0.5715)
							(mid 0.321484 -0.511984)
							(end 0.381 -0.3683)
						)
						(arc
							(start 0.381 0.3683)
							(mid 0.321484 0.511984)
							(end 0.1778 0.5715)
						)
					)
					(width 0)
					(fill yes)
				)
			)
		)
		(pad "S" smd custom
			(at 0.98425 0.9525 90)
			(size 0.1905 0.1905)
			(layers "F.Cu" "F.Mask" "F.Paste")
			(net "GND")
			(options
				(clearance outline)
				(anchor circle)
			)
			(primitives
				(gr_poly
					(pts
						(arc
							(start -0.1778 0.5715)
							(mid -0.321484 0.511984)
							(end -0.381 0.3683)
						)
						(arc
							(start -0.381 -0.3683)
							(mid -0.321484 -0.511984)
							(end -0.1778 -0.5715)
						)
						(arc
							(start 0.1778 -0.5715)
							(mid 0.321484 -0.511984)
							(end 0.381 -0.3683)
						)
						(arc
							(start 0.381 0.3683)
							(mid 0.321484 0.511984)
							(end 0.1778 0.5715)
						)
					)
					(width 0)
					(fill yes)
				)
			)
		)
	)
	(footprint ""
		(layer "F.Cu")
		(at 243.586 -422.148 180)
		(property "Reference" "R370"
			(at 0 0 180)
			(layer "F.SilkS")
			(hide yes)
			(effects
				(font
					(size 1.27 1.27)
				)
			)
		)
		(property "Value" "4K7R2J-2-GP"
			(at 0.064008 -3.993896 180)
			(unlocked yes)
			(layer "F.Fab")
			(hide yes)
			(effects
				(font
					(size 1.016 1.016)
					(thickness 0.1524)
				)
			)
		)
		(property "Device Type" "R402H16"
			(at 0.064008 -5.517896 180)
			(unlocked yes)
			(layer "F.Fab")
			(hide yes)
			(effects
				(font
					(size 1.016 1.016)
					(thickness 0.1524)
				)
			)
		)
		(duplicate_pad_numbers_are_jumpers no)
		(fp_line
			(start 0.508 -0.9398)
			(end -0.508 -0.9398)
			(stroke
				(width 0.1524)
				(type default)
			)
			(layer "F.SilkS")
		)
		(fp_line
			(start -0.508 -0.9398)
			(end -0.508 0.9398)
			(stroke
				(width 0.1524)
				(type default)
			)
			(layer "F.SilkS")
		)
		(fp_rect
			(start -0.508 0.9398)
			(end 0.508 -0.9398)
			(stroke
				(width 0)
				(type default)
			)
			(fill no)
			(layer "F.CrtYd")
		)
		(fp_rect
			(start -0.508 0.9398)
			(end 0.508 -0.9398)
			(stroke
				(width 0)
				(type default)
			)
			(fill no)
			(layer "F.Fab")
		)
		(pad "1" smd custom
			(at 0 -0.4445 180)
			(size 0.1397 0.1397)
			(layers "F.Cu" "F.Mask" "F.Paste")
			(net "P3V3")
			(options
				(clearance outline)
				(anchor circle)
			)
			(primitives
				(gr_poly
					(pts
						(arc
							(start -0.1778 -0.2794)
							(mid -0.249642 -0.249642)
							(end -0.2794 -0.1778)
						)
						(arc
							(start -0.2794 0.1778)
							(mid -0.249642 0.249642)
							(end -0.1778 0.2794)
						)
						(arc
							(start 0.1778 0.2794)
							(mid 0.249642 0.249642)
							(end 0.2794 0.1778)
						)
						(arc
							(start 0.2794 -0.1778)
							(mid 0.249642 -0.249642)
							(end 0.1778 -0.2794)
						)
					)
					(width 0)
					(fill yes)
				)
			)
		)
		(pad "2" smd custom
			(at 0 0.4445 180)
			(size 0.1397 0.1397)
			(layers "F.Cu" "F.Mask" "F.Paste")
			(net "I2C_C_SDA")
			(options
				(clearance outline)
				(anchor circle)
			)
			(primitives
				(gr_poly
					(pts
						(arc
							(start -0.1778 -0.2794)
							(mid -0.249642 -0.249642)
							(end -0.2794 -0.1778)
						)
						(arc
							(start -0.2794 0.1778)
							(mid -0.249642 0.249642)
							(end -0.1778 0.2794)
						)
						(arc
							(start 0.1778 0.2794)
							(mid 0.249642 0.249642)
							(end 0.2794 0.1778)
						)
						(arc
							(start 0.2794 -0.1778)
							(mid 0.249642 -0.249642)
							(end 0.1778 -0.2794)
						)
					)
					(width 0)
					(fill yes)
				)
			)
		)
	)
	(footprint ""
		(layer "F.Cu")
		(at 234.061 -342.007952 90)
		(property "Reference" "R9787"
			(at 0 0 90)
			(layer "F.SilkS")
			(hide yes)
			(effects
				(font
					(size 1.27 1.27)
				)
			)
		)
		(property "Value" "0R2J-2-GP"
			(at 0.064008 -3.993896 90)
			(unlocked yes)
			(layer "F.Fab")
			(hide yes)
			(effects
				(font
					(size 1.016 1.016)
					(thickness 0.1524)
				)
			)
		)
		(property "Device Type" "R402H16"
			(at 0.064008 -5.517896 90)
			(unlocked yes)
			(layer "F.Fab")
			(hide yes)
			(effects
				(font
					(size 1.016 1.016)
					(thickness 0.1524)
				)
			)
		)
		(duplicate_pad_numbers_are_jumpers no)
		(fp_line
			(start 0.508 -0.9398)
			(end -0.508 -0.9398)
			(stroke
				(width 0.1524)
				(type default)
			)
			(layer "F.SilkS")
		)
		(fp_line
			(start -0.508 -0.9398)
			(end -0.508 0.9398)
			(stroke
				(width 0.1524)
				(type default)
			)
			(layer "F.SilkS")
		)
		(fp_rect
			(start -0.508 0.9398)
			(end 0.508 -0.9398)
			(stroke
				(width 0)
				(type default)
			)
			(fill no)
			(layer "F.CrtYd")
		)
		(fp_rect
			(start -0.508 0.9398)
			(end 0.508 -0.9398)
			(stroke
				(width 0)
				(type default)
			)
			(fill no)
			(layer "F.Fab")
		)
		(pad "1" smd custom
			(at 0 -0.4445 90)
			(size 0.1397 0.1397)
			(layers "F.Cu" "F.Mask" "F.Paste")
			(net "ATTN_LED_DR1_AND")
			(options
				(clearance outline)
				(anchor circle)
			)
			(primitives
				(gr_poly
					(pts
						(arc
							(start -0.1778 -0.2794)
							(mid -0.249642 -0.249642)
							(end -0.2794 -0.1778)
						)
						(arc
							(start -0.2794 0.1778)
							(mid -0.249642 0.249642)
							(end -0.1778 0.2794)
						)
						(arc
							(start 0.1778 0.2794)
							(mid 0.249642 0.249642)
							(end 0.2794 0.1778)
						)
						(arc
							(start 0.2794 -0.1778)
							(mid 0.249642 -0.249642)
							(end 0.1778 -0.2794)
						)
					)
					(width 0)
					(fill yes)
				)
			)
		)
		(pad "2" smd custom
			(at 0 0.4445 90)
			(size 0.1397 0.1397)
			(layers "F.Cu" "F.Mask" "F.Paste")
			(net "ATTN_LED_DR1_AND_R")
			(options
				(clearance outline)
				(anchor circle)
			)
			(primitives
				(gr_poly
					(pts
						(arc
							(start -0.1778 -0.2794)
							(mid -0.249642 -0.249642)
							(end -0.2794 -0.1778)
						)
						(arc
							(start -0.2794 0.1778)
							(mid -0.249642 0.249642)
							(end -0.1778 0.2794)
						)
						(arc
							(start 0.1778 0.2794)
							(mid 0.249642 0.249642)
							(end 0.2794 0.1778)
						)
						(arc
							(start 0.2794 -0.1778)
							(mid 0.249642 -0.249642)
							(end 0.1778 -0.2794)
						)
					)
					(width 0)
					(fill yes)
				)
			)
		)
	)
	(footprint ""
		(layer "F.Cu")
		(at 50.038 -14.859)
		(property "Reference" "R583"
			(at 0 0 0)
			(layer "F.SilkS")
			(hide yes)
			(effects
				(font
					(size 1.27 1.27)
				)
			)
		)
		(property "Value" "300KR2F-GP"
			(at 0.064008 -3.993896 0)
			(unlocked yes)
			(layer "F.Fab")
			(hide yes)
			(effects
				(font
					(size 1.016 1.016)
					(thickness 0.1524)
				)
			)
		)
		(property "Device Type" "R402H16"
			(at 0.064008 -5.517896 0)
			(unlocked yes)
			(layer "F.Fab")
			(hide yes)
			(effects
				(font
					(size 1.016 1.016)
					(thickness 0.1524)
				)
			)
		)
		(duplicate_pad_numbers_are_jumpers no)
		(fp_line
			(start -0.508 -0.9398)
			(end -0.508 0.9398)
			(stroke
				(width 0.1524)
				(type default)
			)
			(layer "F.SilkS")
		)
		(fp_line
			(start 0.508 -0.9398)
			(end -0.508 -0.9398)
			(stroke
				(width 0.1524)
				(type default)
			)
			(layer "F.SilkS")
		)
		(fp_rect
			(start -0.508 0.9398)
			(end 0.508 -0.9398)
			(stroke
				(width 0)
				(type default)
			)
			(fill no)
			(layer "F.CrtYd")
		)
		(fp_rect
			(start -0.508 0.9398)
			(end 0.508 -0.9398)
			(stroke
				(width 0)
				(type default)
			)
			(fill no)
			(layer "F.Fab")
		)
		(pad "1" smd custom
			(at 0 -0.4445)
			(size 0.1397 0.1397)
			(layers "F.Cu" "F.Mask" "F.Paste")
			(net "SW_SSD14_N")
			(options
				(clearance outline)
				(anchor circle)
			)
			(primitives
				(gr_poly
					(pts
						(arc
							(start -0.1778 -0.2794)
							(mid -0.249642 -0.249642)
							(end -0.2794 -0.1778)
						)
						(arc
							(start -0.2794 0.1778)
							(mid -0.249642 0.249642)
							(end -0.1778 0.2794)
						)
						(arc
							(start 0.1778 0.2794)
							(mid 0.249642 0.249642)
							(end 0.2794 0.1778)
						)
						(arc
							(start 0.2794 -0.1778)
							(mid 0.249642 -0.249642)
							(end 0.1778 -0.2794)
						)
					)
					(width 0)
					(fill yes)
				)
			)
		)
		(pad "2" smd custom
			(at 0 0.4445)
			(size 0.1397 0.1397)
			(layers "F.Cu" "F.Mask" "F.Paste")
			(net "P12V")
			(options
				(clearance outline)
				(anchor circle)
			)
			(primitives
				(gr_poly
					(pts
						(arc
							(start -0.1778 -0.2794)
							(mid -0.249642 -0.249642)
							(end -0.2794 -0.1778)
						)
						(arc
							(start -0.2794 0.1778)
							(mid -0.249642 0.249642)
							(end -0.1778 0.2794)
						)
						(arc
							(start 0.1778 0.2794)
							(mid 0.249642 0.249642)
							(end 0.2794 0.1778)
						)
						(arc
							(start 0.2794 -0.1778)
							(mid 0.249642 -0.249642)
							(end 0.1778 -0.2794)
						)
					)
					(width 0)
					(fill yes)
				)
			)
		)
	)
	(footprint ""
		(layer "F.Cu")
		(at 52.07 -241.040158 180)
		(property "Reference" "Q64"
			(at 0 0 180)
			(layer "F.SilkS")
			(hide yes)
			(effects
				(font
					(size 1.27 1.27)
				)
			)
		)
		(property "Value" "2N7002A-7-GP"
			(at 0.127 -8.9662 180)
			(unlocked yes)
			(layer "F.Fab")
			(hide yes)
			(effects
				(font
					(size 1.016 1.016)
					(thickness 0.1524)
				)
			)
		)
		(property "Device Type" "SOT23DGS2D4H48"
			(at 0.127 -10.4902 180)
			(unlocked yes)
			(layer "F.Fab")
			(hide yes)
			(effects
				(font
					(size 1.016 1.016)
					(thickness 0.1524)
				)
			)
		)
		(duplicate_pad_numbers_are_jumpers no)
		(fp_line
			(start 1.651 1.778)
			(end 1.651 -1.778)
			(stroke
				(width 0.1524)
				(type default)
			)
			(layer "F.SilkS")
		)
		(fp_line
			(start 1.651 -1.778)
			(end -1.651 -1.778)
			(stroke
				(width 0.1524)
				(type default)
			)
			(layer "F.SilkS")
		)
		(fp_line
			(start -1.651 1.778)
			(end 1.651 1.778)
			(stroke
				(width 0.1524)
				(type default)
			)
			(layer "F.SilkS")
		)
		(fp_line
			(start -1.651 -1.778)
			(end -1.651 1.778)
			(stroke
				(width 0.1524)
				(type default)
			)
			(layer "F.SilkS")
		)
		(fp_poly
			(pts
				(xy -1.778 1.8796) (xy -1.778 -1.8796) (xy 1.778 -1.8796) (xy 1.778 1.8796)
			)
			(stroke
				(width 0)
				(type default)
			)
			(fill no)
			(layer "F.CrtYd")
		)
		(fp_poly
			(pts
				(xy -1.778 1.8796) (xy -1.778 -1.8796) (xy 1.778 -1.8796) (xy 1.778 1.8796)
			)
			(stroke
				(width 0)
				(type default)
			)
			(fill no)
			(layer "F.Fab")
		)
		(pad "D" smd custom
			(at 0 -0.9525 180)
			(size 0.1905 0.1905)
			(layers "F.Cu" "F.Mask" "F.Paste")
			(net "SSD7_CLK0_OE_MOS_N")
			(options
				(clearance outline)
				(anchor circle)
			)
			(primitives
				(gr_poly
					(pts
						(arc
							(start -0.1778 0.5715)
							(mid -0.321484 0.511984)
							(end -0.381 0.3683)
						)
						(arc
							(start -0.381 -0.3683)
							(mid -0.321484 -0.511984)
							(end -0.1778 -0.5715)
						)
						(arc
							(start 0.1778 -0.5715)
							(mid 0.321484 -0.511984)
							(end 0.381 -0.3683)
						)
						(arc
							(start 0.381 0.3683)
							(mid 0.321484 0.511984)
							(end 0.1778 0.5715)
						)
					)
					(width 0)
					(fill yes)
				)
			)
		)
		(pad "G" smd custom
			(at -0.98425 0.9525 180)
			(size 0.1905 0.1905)
			(layers "F.Cu" "F.Mask" "F.Paste")
			(net "SSD7_CLK0_OE_R_N")
			(options
				(clearance outline)
				(anchor circle)
			)
			(primitives
				(gr_poly
					(pts
						(arc
							(start -0.1778 0.5715)
							(mid -0.321484 0.511984)
							(end -0.381 0.3683)
						)
						(arc
							(start -0.381 -0.3683)
							(mid -0.321484 -0.511984)
							(end -0.1778 -0.5715)
						)
						(arc
							(start 0.1778 -0.5715)
							(mid 0.321484 -0.511984)
							(end 0.381 -0.3683)
						)
						(arc
							(start 0.381 0.3683)
							(mid 0.321484 0.511984)
							(end 0.1778 0.5715)
						)
					)
					(width 0)
					(fill yes)
				)
			)
		)
		(pad "S" smd custom
			(at 0.98425 0.9525 180)
			(size 0.1905 0.1905)
			(layers "F.Cu" "F.Mask" "F.Paste")
			(net "GND")
			(options
				(clearance outline)
				(anchor circle)
			)
			(primitives
				(gr_poly
					(pts
						(arc
							(start -0.1778 0.5715)
							(mid -0.321484 0.511984)
							(end -0.381 0.3683)
						)
						(arc
							(start -0.381 -0.3683)
							(mid -0.321484 -0.511984)
							(end -0.1778 -0.5715)
						)
						(arc
							(start 0.1778 -0.5715)
							(mid 0.321484 -0.511984)
							(end 0.381 -0.3683)
						)
						(arc
							(start 0.381 0.3683)
							(mid 0.321484 0.511984)
							(end 0.1778 0.5715)
						)
					)
					(width 0)
					(fill yes)
				)
			)
		)
	)
	(footprint ""
		(layer "F.Cu")
		(at 194.243706 -498.222778 180)
		(property "Reference" "R9495"
			(at 0 0 180)
			(layer "F.SilkS")
			(hide yes)
			(effects
				(font
					(size 1.27 1.27)
				)
			)
		)
		(property "Value" "4K7R2J-2-GP"
			(at 0.064008 -3.993896 180)
			(unlocked yes)
			(layer "F.Fab")
			(hide yes)
			(effects
				(font
					(size 1.016 1.016)
					(thickness 0.1524)
				)
			)
		)
		(property "Device Type" "R402H16"
			(at 0.064008 -5.517896 180)
			(unlocked yes)
			(layer "F.Fab")
			(hide yes)
			(effects
				(font
					(size 1.016 1.016)
					(thickness 0.1524)
				)
			)
		)
		(duplicate_pad_numbers_are_jumpers no)
		(fp_line
			(start 0.508 -0.9398)
			(end -0.508 -0.9398)
			(stroke
				(width 0.1524)
				(type default)
			)
			(layer "F.SilkS")
		)
		(fp_line
			(start -0.508 -0.9398)
			(end -0.508 0.9398)
			(stroke
				(width 0.1524)
				(type default)
			)
			(layer "F.SilkS")
		)
		(fp_rect
			(start -0.508 0.9398)
			(end 0.508 -0.9398)
			(stroke
				(width 0)
				(type default)
			)
			(fill no)
			(layer "F.CrtYd")
		)
		(fp_rect
			(start -0.508 0.9398)
			(end 0.508 -0.9398)
			(stroke
				(width 0)
				(type default)
			)
			(fill no)
			(layer "F.Fab")
		)
		(pad "1" smd custom
			(at 0 -0.4445 180)
			(size 0.1397 0.1397)
			(layers "F.Cu" "F.Mask" "F.Paste")
			(net "P3V3")
			(options
				(clearance outline)
				(anchor circle)
			)
			(primitives
				(gr_poly
					(pts
						(arc
							(start -0.1778 -0.2794)
							(mid -0.249642 -0.249642)
							(end -0.2794 -0.1778)
						)
						(arc
							(start -0.2794 0.1778)
							(mid -0.249642 0.249642)
							(end -0.1778 0.2794)
						)
						(arc
							(start 0.1778 0.2794)
							(mid 0.249642 0.249642)
							(end 0.2794 0.1778)
						)
						(arc
							(start 0.2794 -0.1778)
							(mid 0.249642 -0.249642)
							(end 0.1778 -0.2794)
						)
					)
					(width 0)
					(fill yes)
				)
			)
		)
		(pad "2" smd custom
			(at 0 0.4445 180)
			(size 0.1397 0.1397)
			(layers "F.Cu" "F.Mask" "F.Paste")
			(net "SSD0_PWREN")
			(options
				(clearance outline)
				(anchor circle)
			)
			(primitives
				(gr_poly
					(pts
						(arc
							(start -0.1778 -0.2794)
							(mid -0.249642 -0.249642)
							(end -0.2794 -0.1778)
						)
						(arc
							(start -0.2794 0.1778)
							(mid -0.249642 0.249642)
							(end -0.1778 0.2794)
						)
						(arc
							(start 0.1778 0.2794)
							(mid 0.249642 0.249642)
							(end 0.2794 0.1778)
						)
						(arc
							(start 0.2794 -0.1778)
							(mid 0.249642 -0.249642)
							(end 0.1778 -0.2794)
						)
					)
					(width 0)
					(fill yes)
				)
			)
		)
	)
)
